# T6G (Grand Teton) — schematic netlist excerpt (pin names and nets, part order shuffled) for the footprints in the layout excerpt that follows; sources: Cadence DE-HDL packaged netlist, KiCad conversion of 04192023_DAF0TMB3IC0_F0TG_MB_C_brd_V02_OCP.brd

PR3806  Q_RES  6.8K 1% CHIP  pkg 0402LF  page 140 : A = P12V_OCP_UV_2 ; B = P12V_OCP_OV_2
C853  Q_CAP_DIFFBUS  DIFF BUS_0.22UF 6.3V 20% X6S  pkg C0201  page 64 : \1\ = P5E_CPU0_P2_TX_C_DP<8> ; \2\ = P5E_CPU0_P2_TX_DP<8>
C1841  Q_CAP  0.1UF 25V 10% X7R  pkg 0402  page 139 : A = P3V3_AUX ; B = GND

(kicad_pcb
	(version 20260206)
	(generator "pcbnew")
	(generator_version "10.0")
	(general
		(thickness 1.6)
		(legacy_teardrops no)
	)
	(paper "A4")
	(title_block
		(title "04192023_DAF0TMB3IC0_F0TG_MB_C_brd_V02_OCP.brd")
		(comment 1 "Grand Teton / footprints 1063-1065 of 8354")
	)
	(layers
		(0 "F.Cu" signal "TOP")
		(4 "In1.Cu" signal "GND")
		(6 "In2.Cu" signal "IN1")
		(8 "In3.Cu" signal "GND1")
		(10 "In4.Cu" signal "IN2")
		(12 "In5.Cu" signal "GND2")
		(14 "In6.Cu" signal "IN3")
		(16 "In7.Cu" signal "GND3")
		(18 "In8.Cu" signal "VCC")
		(20 "In9.Cu" signal "VCC1")
		(22 "In10.Cu" signal "GND4")
		(24 "In11.Cu" signal "IN4")
		(26 "In12.Cu" signal "GND5")
		(28 "In13.Cu" signal "IN5")
		(30 "In14.Cu" signal "GND6")
		(32 "In15.Cu" signal "IN6")
		(34 "In16.Cu" signal "GND7")
		(2 "B.Cu" signal "BOTTOM")
		(9 "F.Adhes" user "F.Adhesive")
		(11 "B.Adhes" user "B.Adhesive")
		(13 "F.Paste" user "Package Geometry/Pastemask Top")
		(15 "B.Paste" user "Package Geometry/Pastemask Bottom")
		(5 "F.SilkS" user "Ref Des/Silkscreen Top")
		(7 "B.SilkS" user "Ref Des/Silkscreen Bottom")
		(1 "F.Mask" user "Board Geometry/Soldermask Top")
		(3 "B.Mask" user "Board Geometry/Soldermask Bottom")
		(17 "Dwgs.User" user "User.Drawings")
		(19 "Cmts.User" user "User.Comments")
		(21 "Eco1.User" user "User.Eco1")
		(23 "Eco2.User" user "User.Eco2")
		(25 "Edge.Cuts" user "Board Geometry/Outline")
		(27 "Margin" user)
		(31 "F.CrtYd" user "Package Geometry/Place Bound Top")
		(29 "B.CrtYd" user "Package Geometry/Place Bound Bottom")
		(35 "F.Fab" user "Ref Des/Assembly Top")
		(33 "B.Fab" user "Ref Des/Assembly Bottom")
	)
	(footprint ""
		(layer "F.Cu")
		(at 412.23184 -381.41783 -90)
		(property "Reference" "C853"
			(at 0 0 270)
			(layer "F.SilkS")
			(hide yes)
			(effects
				(font
					(size 1.27 1.27)
				)
			)
		)
		(property "Value" ""
			(at 0 0 270)
			(layer "F.Fab")
			(effects
				(font
					(size 1.27 1.27)
				)
			)
		)
		(duplicate_pad_numbers_are_jumpers no)
		(fp_line
			(start -0.299974 0.150114)
			(end -0.299974 -0.150114)
			(stroke
				(width 0.1)
				(type default)
			)
			(layer "F.Fab")
		)
		(fp_line
			(start 0.299974 0.150114)
			(end -0.299974 0.150114)
			(stroke
				(width 0.1)
				(type default)
			)
			(layer "F.Fab")
		)
		(fp_line
			(start -0.299974 -0.150114)
			(end 0.299974 -0.150114)
			(stroke
				(width 0.1)
				(type default)
			)
			(layer "F.Fab")
		)
		(fp_line
			(start 0.299974 -0.150114)
			(end 0.299974 0.150114)
			(stroke
				(width 0.1)
				(type default)
			)
			(layer "F.Fab")
		)
		(pad "1" smd rect
			(at -0.2667 0 270)
			(size 0.3048 0.381)
			(layers "F.Cu" "F.Mask" "F.Paste")
			(net "P5E_CPU0_P2_TX_C_DP<8>")
		)
		(pad "2" smd rect
			(at 0.2667 0 270)
			(size 0.3048 0.381)
			(layers "F.Cu" "F.Mask" "F.Paste")
			(net "P5E_CPU0_P2_TX_DP<8>")
		)
	)
	(footprint ""
		(layer "F.Cu")
		(at 51.577494 -32.277558 90)
		(property "Reference" "C1841"
			(at 0 0 90)
			(layer "F.SilkS")
			(hide yes)
			(effects
				(font
					(size 1.27 1.27)
				)
			)
		)
		(property "Value" ""
			(at 0 0 90)
			(layer "F.Fab")
			(effects
				(font
					(size 1.27 1.27)
				)
			)
		)
		(duplicate_pad_numbers_are_jumpers no)
		(fp_line
			(start 0.7874 -0.4064)
			(end 0.7874 0.4064)
			(stroke
				(width 0.1524)
				(type default)
			)
			(layer "F.SilkS")
		)
		(fp_line
			(start -0.7874 -0.4064)
			(end 0.7874 -0.4064)
			(stroke
				(width 0.1524)
				(type default)
			)
			(layer "F.SilkS")
		)
		(fp_line
			(start 0.7874 0.4064)
			(end -0.7874 0.4064)
			(stroke
				(width 0.1524)
				(type default)
			)
			(layer "F.SilkS")
		)
		(fp_line
			(start -0.7874 0.4064)
			(end -0.7874 -0.4064)
			(stroke
				(width 0.1524)
				(type default)
			)
			(layer "F.SilkS")
		)
		(fp_line
			(start -0.12065 -0.305054)
			(end -0.12065 -0.2794)
			(stroke
				(width 0.1)
				(type default)
			)
			(layer "F.Fab")
		)
		(fp_line
			(start -0.67945 -0.305054)
			(end -0.12065 -0.305054)
			(stroke
				(width 0.1)
				(type default)
			)
			(layer "F.Fab")
		)
		(fp_line
			(start 0.67945 -0.3048)
			(end 0.67945 0.3048)
			(stroke
				(width 0.1)
				(type default)
			)
			(layer "F.Fab")
		)
		(fp_line
			(start 0.12065 -0.3048)
			(end 0.67945 -0.3048)
			(stroke
				(width 0.1)
				(type default)
			)
			(layer "F.Fab")
		)
		(fp_line
			(start 0.12065 -0.2794)
			(end 0.12065 -0.3048)
			(stroke
				(width 0.1)
				(type default)
			)
			(layer "F.Fab")
		)
		(fp_line
			(start -0.12065 -0.2794)
			(end 0.12065 -0.2794)
			(stroke
				(width 0.1)
				(type default)
			)
			(layer "F.Fab")
		)
		(fp_line
			(start 0.120396 0.2794)
			(end -0.12065 0.2794)
			(stroke
				(width 0.1)
				(type default)
			)
			(layer "F.Fab")
		)
		(fp_line
			(start -0.12065 0.2794)
			(end -0.12065 0.3048)
			(stroke
				(width 0.1)
				(type default)
			)
			(layer "F.Fab")
		)
		(fp_line
			(start 0.67945 0.3048)
			(end 0.120396 0.3048)
			(stroke
				(width 0.1)
				(type default)
			)
			(layer "F.Fab")
		)
		(fp_line
			(start 0.120396 0.3048)
			(end 0.120396 0.2794)
			(stroke
				(width 0.1)
				(type default)
			)
			(layer "F.Fab")
		)
		(fp_line
			(start -0.12065 0.3048)
			(end -0.67945 0.3048)
			(stroke
				(width 0.1)
				(type default)
			)
			(layer "F.Fab")
		)
		(fp_line
			(start -0.67945 0.3048)
			(end -0.67945 -0.305054)
			(stroke
				(width 0.1)
				(type default)
			)
			(layer "F.Fab")
		)
		(pad "1" smd circle
			(at -0.40005 0 90)
			(size 0 0)
			(layers "F.Cu" "F.Mask" "F.Paste")
			(net "P3V3_AUX")
		)
		(pad "2" smd circle
			(at 0.40005 0 90)
			(size 0 0)
			(layers "F.Cu" "F.Mask" "F.Paste")
			(net "GND")
		)
	)
	(footprint ""
		(layer "F.Cu")
		(at 77.537564 -17.680178 -90)
		(property "Reference" "PR3806"
			(at 0 0 270)
			(layer "F.SilkS")
			(hide yes)
			(effects
				(font
					(size 1.27 1.27)
				)
			)
		)
		(property "Value" ""
			(at 0 0 270)
			(layer "F.Fab")
			(effects
				(font
					(size 1.27 1.27)
				)
			)
		)
		(duplicate_pad_numbers_are_jumpers no)
		(fp_line
			(start -0.7874 0.4064)
			(end -0.7874 -0.4064)
			(stroke
				(width 0.1524)
				(type default)
			)
			(layer "F.SilkS")
		)
		(fp_line
			(start 0.7874 0.4064)
			(end -0.7874 0.4064)
			(stroke
				(width 0.1524)
				(type default)
			)
			(layer "F.SilkS")
		)
		(fp_line
			(start -0.7874 -0.4064)
			(end 0.7874 -0.4064)
			(stroke
				(width 0.1524)
				(type default)
			)
			(layer "F.SilkS")
		)
		(fp_line
			(start 0.7874 -0.4064)
			(end 0.7874 0.4064)
			(stroke
				(width 0.1524)
				(type default)
			)
			(layer "F.SilkS")
		)
		(fp_line
			(start -0.67945 0.3048)
			(end -0.67945 -0.305054)
			(stroke
				(width 0.1)
				(type default)
			)
			(layer "F.Fab")
		)
		(fp_line
			(start -0.12065 0.3048)
			(end -0.67945 0.3048)
			(stroke
				(width 0.1)
				(type default)
			)
			(layer "F.Fab")
		)
		(fp_line
			(start 0.120396 0.3048)
			(end 0.120396 0.2794)
			(stroke
				(width 0.1)
				(type default)
			)
			(layer "F.Fab")
		)
		(fp_line
			(start 0.67945 0.3048)
			(end 0.120396 0.3048)
			(stroke
				(width 0.1)
				(type default)
			)
			(layer "F.Fab")
		)
		(fp_line
			(start -0.12065 0.2794)
			(end -0.12065 0.3048)
			(stroke
				(width 0.1)
				(type default)
			)
			(layer "F.Fab")
		)
		(fp_line
			(start 0.120396 0.2794)
			(end -0.12065 0.2794)
			(stroke
				(width 0.1)
				(type default)
			)
			(layer "F.Fab")
		)
		(fp_line
			(start -0.12065 -0.2794)
			(end 0.12065 -0.2794)
			(stroke
				(width 0.1)
				(type default)
			)
			(layer "F.Fab")
		)
		(fp_line
			(start 0.12065 -0.2794)
			(end 0.12065 -0.3048)
			(stroke
				(width 0.1)
				(type default)
			)
			(layer "F.Fab")
		)
		(fp_line
			(start 0.12065 -0.3048)
			(end 0.67945 -0.3048)
			(stroke
				(width 0.1)
				(type default)
			)
			(layer "F.Fab")
		)
		(fp_line
			(start 0.67945 -0.3048)
			(end 0.67945 0.3048)
			(stroke
				(width 0.1)
				(type default)
			)
			(layer "F.Fab")
		)
		(fp_line
			(start -0.67945 -0.305054)
			(end -0.12065 -0.305054)
			(stroke
				(width 0.1)
				(type default)
			)
			(layer "F.Fab")
		)
		(fp_line
			(start -0.12065 -0.305054)
			(end -0.12065 -0.2794)
			(stroke
				(width 0.1)
				(type default)
			)
			(layer "F.Fab")
		)
		(pad "1" smd circle
			(at -0.40005 0 270)
			(size 0 0)
			(layers "F.Cu" "F.Mask" "F.Paste")
			(net "P12V_OCP_UV_2")
		)
		(pad "2" smd circle
			(at 0.40005 0 270)
			(size 0 0)
			(layers "F.Cu" "F.Mask" "F.Paste")
			(net "P12V_OCP_OV_2")
		)
	)
)
